# T6G (Grand Teton) — schematic netlist excerpt (pin names and nets, part order shuffled) for the footprints in the layout excerpt that follows; sources: Cadence DE-HDL packaged netlist, KiCad conversion of 04192023_DAF0TMB3IC0_F0TG_MB_C_brd_V02_OCP.brd

R628  Q_RES  51.1 1% EMPTY  pkg 0201LF  page 320 : A = CLK_100M_RETIMER_CPU1_P0_DP ; B = GND
C751  Q_CAP_DIFFBUS  DIFF BUS_0.22UF 6.3V 20% X6S  pkg C0201  page 66 : \1\ = P5E_CPU1_P2_TX_C_DP<11> ; \2\ = P5E_CPU1_P2_TX_DP<11>

U8082  74LVC1G126SE7  74LVC1G126SE-7 IC  pkg SOT353_0-65_2X1-25  page 133
  OE  = PU_OCP_SFF_WAKE_OE
  A  = IRQ_LVC3_OCP_SFF_WAKE_N
  GND  = GND
  Y  = OCP_SFF_WAKE_BUFF_N
  VCC  = P3V3_AUX

C6519  Q_CAP_DIFFBUS  DIFF BUS_0.22UF 6.3V 20% X6S  pkg C0201  page 275 : \1\ = P5E_CPU0_P0_TX_BUF_C_DP<9> ; \2\ = P5E_CPU0_P0_TX_BUF_DP<9>

(kicad_pcb
	(version 20260206)
	(generator "pcbnew")
	(generator_version "10.0")
	(general
		(thickness 1.6)
		(legacy_teardrops no)
	)
	(paper "A4")
	(title_block
		(title "04192023_DAF0TMB3IC0_F0TG_MB_C_brd_V02_OCP.brd")
		(comment 1 "Grand Teton / footprints 2910-2913 of 8354")
	)
	(layers
		(0 "F.Cu" signal "TOP")
		(4 "In1.Cu" signal "GND")
		(6 "In2.Cu" signal "IN1")
		(8 "In3.Cu" signal "GND1")
		(10 "In4.Cu" signal "IN2")
		(12 "In5.Cu" signal "GND2")
		(14 "In6.Cu" signal "IN3")
		(16 "In7.Cu" signal "GND3")
		(18 "In8.Cu" signal "VCC")
		(20 "In9.Cu" signal "VCC1")
		(22 "In10.Cu" signal "GND4")
		(24 "In11.Cu" signal "IN4")
		(26 "In12.Cu" signal "GND5")
		(28 "In13.Cu" signal "IN5")
		(30 "In14.Cu" signal "GND6")
		(32 "In15.Cu" signal "IN6")
		(34 "In16.Cu" signal "GND7")
		(2 "B.Cu" signal "BOTTOM")
		(9 "F.Adhes" user "F.Adhesive")
		(11 "B.Adhes" user "B.Adhesive")
		(13 "F.Paste" user "Package Geometry/Pastemask Top")
		(15 "B.Paste" user "Package Geometry/Pastemask Bottom")
		(5 "F.SilkS" user "Ref Des/Silkscreen Top")
		(7 "B.SilkS" user "Ref Des/Silkscreen Bottom")
		(1 "F.Mask" user "Board Geometry/Soldermask Top")
		(3 "B.Mask" user "Board Geometry/Soldermask Bottom")
		(17 "Dwgs.User" user "User.Drawings")
		(19 "Cmts.User" user "User.Comments")
		(21 "Eco1.User" user "User.Eco1")
		(23 "Eco2.User" user "User.Eco2")
		(25 "Edge.Cuts" user "Board Geometry/Outline")
		(27 "Margin" user)
		(31 "F.CrtYd" user "Package Geometry/Place Bound Top")
		(29 "B.CrtYd" user "Package Geometry/Place Bound Bottom")
		(35 "F.Fab" user "Ref Des/Assembly Top")
		(33 "B.Fab" user "Ref Des/Assembly Bottom")
	)
	(footprint ""
		(layer "F.Cu")
		(at 458.86116 -37.91585)
		(property "Reference" "U8082"
			(at -2.2733 1.990852 0)
			(unlocked yes)
			(layer "F.SilkS")
			(effects
				(font
					(size 0.7874 0.5842)
					(thickness 0.1524)
				)
				(justify left)
			)
		)
		(property "Value" ""
			(at 0 0 0)
			(layer "F.Fab")
			(effects
				(font
					(size 1.27 1.27)
				)
			)
		)
		(duplicate_pad_numbers_are_jumpers no)
		(fp_line
			(start -1.400048 1.100074)
			(end -1.400048 -1.100074)
			(stroke
				(width 0.1524)
				(type default)
			)
			(layer "F.SilkS")
		)
		(fp_line
			(start 1.400048 -1.100074)
			(end -1.400048 -1.100074)
			(stroke
				(width 0.1524)
				(type default)
			)
			(layer "F.SilkS")
		)
		(fp_line
			(start 1.400048 -1.100074)
			(end 1.400048 1.100074)
			(stroke
				(width 0.1524)
				(type default)
			)
			(layer "F.SilkS")
		)
		(fp_line
			(start 1.400048 1.100074)
			(end -1.400048 1.100074)
			(stroke
				(width 0.1524)
				(type default)
			)
			(layer "F.SilkS")
		)
		(fp_poly
			(pts
				(xy -2.055368 -1.405128) (xy -1.705102 -1.755394) (xy -1.529842 -1.229868)
			)
			(stroke
				(width 0)
				(type default)
			)
			(fill yes)
			(layer "F.SilkS")
		)
		(fp_line
			(start -0.674878 -1.100074)
			(end 0.674878 -1.100074)
			(stroke
				(width 0.1)
				(type default)
			)
			(layer "F.Fab")
		)
		(fp_line
			(start -0.674878 1.100074)
			(end -0.674878 -1.100074)
			(stroke
				(width 0.1)
				(type default)
			)
			(layer "F.Fab")
		)
		(fp_line
			(start 0.674878 -1.100074)
			(end 0.674878 1.100074)
			(stroke
				(width 0.1)
				(type default)
			)
			(layer "F.Fab")
		)
		(fp_line
			(start 0.674878 1.100074)
			(end -0.674878 1.100074)
			(stroke
				(width 0.1)
				(type default)
			)
			(layer "F.Fab")
		)
		(fp_poly
			(pts
				(xy -1.590548 -0.649986) (xy -2.606548 -1.157986) (xy -2.606548 -0.141986)
			)
			(stroke
				(width 0)
				(type default)
			)
			(fill yes)
			(layer "F.Fab")
		)
		(pad "1" smd rect
			(at -0.94996 -0.649986 270)
			(size 0.4318 0.6096)
			(layers "F.Cu" "F.Mask" "F.Paste")
			(net "PU_OCP_SFF_WAKE_OE")
		)
		(pad "2" smd rect
			(at -0.94996 0 270)
			(size 0.4318 0.6096)
			(layers "F.Cu" "F.Mask" "F.Paste")
			(net "IRQ_LVC3_OCP_SFF_WAKE_N")
		)
		(pad "3" smd rect
			(at -0.94996 0.649986 270)
			(size 0.4318 0.6096)
			(layers "F.Cu" "F.Mask" "F.Paste")
			(net "GND")
		)
		(pad "4" smd rect
			(at 0.94996 0.649986 270)
			(size 0.4318 0.6096)
			(layers "F.Cu" "F.Mask" "F.Paste")
			(net "OCP_SFF_WAKE_BUFF_N")
		)
		(pad "5" smd rect
			(at 0.94996 -0.649986 270)
			(size 0.4318 0.6096)
			(layers "F.Cu" "F.Mask" "F.Paste")
			(net "P3V3_AUX")
		)
	)
	(footprint ""
		(layer "F.Cu")
		(at 332.252066 -416.899344 -90)
		(property "Reference" "C6519"
			(at 0 0 270)
			(layer "F.SilkS")
			(hide yes)
			(effects
				(font
					(size 1.27 1.27)
				)
			)
		)
		(property "Value" ""
			(at 0 0 270)
			(layer "F.Fab")
			(effects
				(font
					(size 1.27 1.27)
				)
			)
		)
		(duplicate_pad_numbers_are_jumpers no)
		(fp_line
			(start -0.299974 0.150114)
			(end -0.299974 -0.150114)
			(stroke
				(width 0.1)
				(type default)
			)
			(layer "F.Fab")
		)
		(fp_line
			(start 0.299974 0.150114)
			(end -0.299974 0.150114)
			(stroke
				(width 0.1)
				(type default)
			)
			(layer "F.Fab")
		)
		(fp_line
			(start -0.299974 -0.150114)
			(end 0.299974 -0.150114)
			(stroke
				(width 0.1)
				(type default)
			)
			(layer "F.Fab")
		)
		(fp_line
			(start 0.299974 -0.150114)
			(end 0.299974 0.150114)
			(stroke
				(width 0.1)
				(type default)
			)
			(layer "F.Fab")
		)
		(pad "1" smd rect
			(at -0.2667 0 270)
			(size 0.3048 0.381)
			(layers "F.Cu" "F.Mask" "F.Paste")
			(net "P5E_CPU0_P0_TX_BUF_C_DP<9>")
		)
		(pad "2" smd rect
			(at 0.2667 0 270)
			(size 0.3048 0.381)
			(layers "F.Cu" "F.Mask" "F.Paste")
			(net "P5E_CPU0_P0_TX_BUF_DP<9>")
		)
	)
	(footprint ""
		(layer "F.Cu")
		(at 163.039044 -373.03583 -90)
		(property "Reference" "C751"
			(at 0 0 270)
			(layer "F.SilkS")
			(hide yes)
			(effects
				(font
					(size 1.27 1.27)
				)
			)
		)
		(property "Value" ""
			(at 0 0 270)
			(layer "F.Fab")
			(effects
				(font
					(size 1.27 1.27)
				)
			)
		)
		(duplicate_pad_numbers_are_jumpers no)
		(fp_line
			(start -0.299974 0.150114)
			(end -0.299974 -0.150114)
			(stroke
				(width 0.1)
				(type default)
			)
			(layer "F.Fab")
		)
		(fp_line
			(start 0.299974 0.150114)
			(end -0.299974 0.150114)
			(stroke
				(width 0.1)
				(type default)
			)
			(layer "F.Fab")
		)
		(fp_line
			(start -0.299974 -0.150114)
			(end 0.299974 -0.150114)
			(stroke
				(width 0.1)
				(type default)
			)
			(layer "F.Fab")
		)
		(fp_line
			(start 0.299974 -0.150114)
			(end 0.299974 0.150114)
			(stroke
				(width 0.1)
				(type default)
			)
			(layer "F.Fab")
		)
		(pad "1" smd rect
			(at -0.2667 0 270)
			(size 0.3048 0.381)
			(layers "F.Cu" "F.Mask" "F.Paste")
			(net "P5E_CPU1_P2_TX_C_DP<11>")
		)
		(pad "2" smd rect
			(at 0.2667 0 270)
			(size 0.3048 0.381)
			(layers "F.Cu" "F.Mask" "F.Paste")
			(net "P5E_CPU1_P2_TX_DP<11>")
		)
	)
	(footprint ""
		(layer "F.Cu")
		(at 43.543982 -388.030974 90)
		(property "Reference" "R628"
			(at 0 0 90)
			(layer "F.SilkS")
			(hide yes)
			(effects
				(font
					(size 1.27 1.27)
				)
			)
		)
		(property "Value" ""
			(at 0 0 90)
			(layer "F.Fab")
			(effects
				(font
					(size 1.27 1.27)
				)
			)
		)
		(duplicate_pad_numbers_are_jumpers no)
		(fp_line
			(start 0.32512 -0.175006)
			(end 0.32512 0.175006)
			(stroke
				(width 0.1)
				(type default)
			)
			(layer "F.Fab")
		)
		(fp_line
			(start -0.32512 -0.175006)
			(end 0.32512 -0.175006)
			(stroke
				(width 0.1)
				(type default)
			)
			(layer "F.Fab")
		)
		(fp_line
			(start 0.32512 0.175006)
			(end -0.32512 0.175006)
			(stroke
				(width 0.1)
				(type default)
			)
			(layer "F.Fab")
		)
		(fp_line
			(start -0.32512 0.175006)
			(end -0.32512 -0.175006)
			(stroke
				(width 0.1)
				(type default)
			)
			(layer "F.Fab")
		)
		(pad "1" smd rect
			(at -0.2667 0 90)
			(size 0.3048 0.381)
			(layers "F.Cu" "F.Mask" "F.Paste")
			(net "CLK_100M_RETIMER_CPU1_P0_DP")
		)
		(pad "2" smd rect
			(at 0.2667 0 270)
			(size 0.3048 0.381)
			(layers "F.Cu" "F.Mask" "F.Paste")
			(net "GND")
		)
	)
)
